(kicad_pcb
	(version 20241229)
	(generator "pcbnew")
	(generator_version "9.0")
	(general
		(thickness 1.294)
		(legacy_teardrops no)
	)
	(paper "A3")
	(title_block
		(title "Kintex 410T devboard")
		(date "2024-04-03")
		(rev "1.1.2")
		(comment 9 "footprints 886-891 of 975")
	)
	(layers
		(0 "F.Cu" mixed)
		(4 "In1.Cu" power)
		(6 "In2.Cu" power)
		(8 "In3.Cu" mixed)
		(10 "In4.Cu" power)
		(12 "In5.Cu" mixed)
		(14 "In6.Cu" power)
		(16 "In7.Cu" mixed)
		(18 "In8.Cu" power)
		(2 "B.Cu" mixed)
		(9 "F.Adhes" user "F.Adhesive")
		(11 "B.Adhes" user "B.Adhesive")
		(13 "F.Paste" user)
		(15 "B.Paste" user)
		(5 "F.SilkS" user "F.Silkscreen")
		(7 "B.SilkS" user "B.Silkscreen")
		(1 "F.Mask" user)
		(3 "B.Mask" user)
		(17 "Dwgs.User" user "User.Drawings")
		(19 "Cmts.User" user "User.Comments")
		(21 "Eco1.User" user "User.Eco1")
		(23 "Eco2.User" user "User.Eco2")
		(25 "Edge.Cuts" user)
		(27 "Margin" user)
		(31 "F.CrtYd" user "F.Courtyard")
		(29 "B.CrtYd" user "B.Courtyard")
		(35 "F.Fab" user)
		(33 "B.Fab" user)
	)
	(footprint "antmicro-footprints:R_0402_1005Metric"
		(layer "B.Cu")
		(at 170 146.575 180)
		(descr "Resistor SMD 0402")
		(tags "resistor SMD 0402")
		(property "Reference" "R32"
			(at -3.025 -0.45 0)
			(layer "B.SilkS")
			(effects
				(font
					(size 0.7 0.7)
					(thickness 0.15)
				)
				(justify left bottom mirror)
			)
		)
		(property "Value" "R_100R_0402"
			(at 0 -1.4 0)
			(layer "B.Fab")
			(effects
				(font
					(size 0.7 0.7)
					(thickness 0.15)
				)
				(justify left bottom mirror)
			)
		)
		(property "Description" "SMD Chip Resistor, 100 ohm, ± 1%, 62.5 mW, 0402 [1005 Metric], Thick Film, General Purpose"
			(at 0 0 180)
			(layer "F.Fab")
			(hide yes)
			(effects
				(font
					(size 1.27 1.27)
					(thickness 0.15)
				)
			)
		)
		(property "Author" "Antmicro"
			(at 340 293.15 0)
			(layer "B.Fab")
			(hide yes)
			(effects
				(font
					(size 1 1)
					(thickness 0.15)
				)
				(justify mirror)
			)
		)
		(property "License" "Apache-2.0"
			(at 340 293.15 0)
			(layer "B.Fab")
			(hide yes)
			(effects
				(font
					(size 1 1)
					(thickness 0.15)
				)
				(justify mirror)
			)
		)
		(property "MPN" "CR0402-FX-1000GLF"
			(at 340 293.15 0)
			(layer "B.Fab")
			(hide yes)
			(effects
				(font
					(size 1 1)
					(thickness 0.15)
				)
				(justify mirror)
			)
		)
		(property "Manufacturer" "Bourns"
			(at 340 293.15 0)
			(layer "B.Fab")
			(hide yes)
			(effects
				(font
					(size 1 1)
					(thickness 0.15)
				)
				(justify mirror)
			)
		)
		(property "Tolerance" "1%"
			(at 340 293.15 0)
			(layer "B.Fab")
			(hide yes)
			(effects
				(font
					(size 1 1)
					(thickness 0.15)
				)
				(justify mirror)
			)
		)
		(property "Val" "100R"
			(at 340 293.15 0)
			(layer "B.Fab")
			(hide yes)
			(effects
				(font
					(size 1 1)
					(thickness 0.15)
				)
				(justify mirror)
			)
		)
		(sheetname "DRAM + SRAM")
		(sheetfile "ram.kicad_sch")
		(attr smd)
		(fp_rect
			(start -0.925 0.47)
			(end 0.925 -0.47)
			(stroke
				(width 0.05)
				(type default)
			)
			(fill no)
			(layer "B.CrtYd")
		)
		(fp_rect
			(start -0.5 0.25)
			(end 0.5 -0.25)
			(stroke
				(width 0.15)
				(type solid)
			)
			(fill no)
			(layer "B.Fab")
		)
		(pad "1" smd roundrect
			(at -0.48 0 180)
			(size 0.59 0.64)
			(layers "B.Cu" "B.Mask" "B.Paste")
			(roundrect_rratio 0.25)
			(net 551 "/DRAM + SRAM/DDR.CK_P")
			(pintype "passive")
		)
		(pad "2" smd roundrect
			(at 0.48 0 180)
			(size 0.59 0.64)
			(layers "B.Cu" "B.Mask" "B.Paste")
			(roundrect_rratio 0.25)
			(net 552 "/DRAM + SRAM/DDR.CK_N")
			(pintype "passive")
		)
	)
	(footprint "antmicro-footprints:R_0402_1005Metric"
		(layer "B.Cu")
		(at 181.05 170.63 -90)
		(descr "Resistor SMD 0402")
		(tags "resistor SMD 0402")
		(property "Reference" "R295"
			(at 0.77 -0.375 90)
			(layer "B.SilkS")
			(effects
				(font
					(size 0.7 0.7)
					(thickness 0.15)
				)
				(justify left bottom mirror)
			)
		)
		(property "Value" "R_0R_0402"
			(at 0 -1.4 90)
			(layer "B.Fab")
			(effects
				(font
					(size 0.7 0.7)
					(thickness 0.15)
				)
				(justify left bottom mirror)
			)
		)
		(property "Description" "SMD Chip Resistor, Jumper, 0 ohm, 100 mW, 0402 [1005 Metric], Thick Film, General Purpose"
			(at 0 0 270)
			(layer "F.Fab")
			(hide yes)
			(effects
				(font
					(size 1.27 1.27)
					(thickness 0.15)
				)
			)
		)
		(property "Author" "Antmicro"
			(at 10.42 351.68 0)
			(layer "B.Fab")
			(hide yes)
			(effects
				(font
					(size 1 1)
					(thickness 0.15)
				)
				(justify mirror)
			)
		)
		(property "Current" "1A"
			(at 10.42 351.68 0)
			(layer "B.Fab")
			(hide yes)
			(effects
				(font
					(size 1 1)
					(thickness 0.15)
				)
				(justify mirror)
			)
		)
		(property "DNP" "DNP"
			(at 10.42 351.68 0)
			(layer "B.Fab")
			(hide yes)
			(effects
				(font
					(size 1 1)
					(thickness 0.15)
				)
				(justify mirror)
			)
		)
		(property "License" "Apache-2.0"
			(at 10.42 351.68 0)
			(layer "B.Fab")
			(hide yes)
			(effects
				(font
					(size 1 1)
					(thickness 0.15)
				)
				(justify mirror)
			)
		)
		(property "MPN" "ERJ2GE0R00X"
			(at 10.42 351.68 0)
			(layer "B.Fab")
			(hide yes)
			(effects
				(font
					(size 1 1)
					(thickness 0.15)
				)
				(justify mirror)
			)
		)
		(property "Manufacturer" "Panasonic"
			(at 10.42 351.68 0)
			(layer "B.Fab")
			(hide yes)
			(effects
				(font
					(size 1 1)
					(thickness 0.15)
				)
				(justify mirror)
			)
		)
		(property "Tolerance" ""
			(at 10.42 351.68 0)
			(layer "B.Fab")
			(hide yes)
			(effects
				(font
					(size 1 1)
					(thickness 0.15)
				)
				(justify mirror)
			)
		)
		(property "Val" "0R"
			(at 10.42 351.68 0)
			(layer "B.Fab")
			(hide yes)
			(effects
				(font
					(size 1 1)
					(thickness 0.15)
				)
				(justify mirror)
			)
		)
		(property "dnp" ""
			(at 10.42 351.68 0)
			(layer "B.Fab")
			(hide yes)
			(effects
				(font
					(size 1 1)
					(thickness 0.15)
				)
				(justify mirror)
			)
		)
		(property "exclude_from_bom" ""
			(at 10.42 351.68 0)
			(layer "B.Fab")
			(hide yes)
			(effects
				(font
					(size 1 1)
					(thickness 0.15)
				)
				(justify mirror)
			)
		)
		(sheetname "DC-DC Converters")
		(sheetfile "dc-dc.kicad_sch")
		(attr smd exclude_from_bom)
		(fp_rect
			(start -0.925 0.47)
			(end 0.925 -0.47)
			(stroke
				(width 0.05)
				(type default)
			)
			(fill no)
			(layer "B.CrtYd")
		)
		(fp_rect
			(start -0.5 0.25)
			(end 0.5 -0.25)
			(stroke
				(width 0.15)
				(type solid)
			)
			(fill no)
			(layer "B.Fab")
		)
		(pad "1" smd roundrect
			(at -0.48 0 270)
			(size 0.59 0.64)
			(layers "B.Cu" "B.Mask" "B.Paste")
			(roundrect_rratio 0.25)
			(net 957 "/DC-DC Converters/FB6")
			(pintype "passive")
		)
		(pad "2" smd roundrect
			(at 0.48 0 270)
			(size 0.59 0.64)
			(layers "B.Cu" "B.Mask" "B.Paste")
			(roundrect_rratio 0.25)
			(net 958 "/DC-DC Converters/FB5")
			(pintype "passive")
		)
	)
	(footprint "antmicro-footprints:SC70-3"
		(layer "B.Cu")
		(at 240.55 142.05 90)
		(property "Reference" "Q17"
			(at 0.725 -1.376 270)
			(layer "B.SilkS")
			(effects
				(font
					(size 0.7 0.7)
					(thickness 0.15)
				)
				(justify left bottom mirror)
			)
		)
		(property "Value" "BSS138PW"
			(at 0 -2.3 270)
			(layer "B.Fab")
			(effects
				(font
					(size 0.7 0.7)
					(thickness 0.15)
				)
				(justify left bottom mirror)
			)
		)
		(property "Description" "Power MOSFET, N Channel, 60 V, 320 mA, 0.9 ohm, SOT-323, Surface Mount"
			(at 0 0 90)
			(layer "F.Fab")
			(hide yes)
			(effects
				(font
					(size 1.27 1.27)
					(thickness 0.15)
				)
			)
		)
		(property "Author" "Antmicro"
			(at 382.6 -98.5 0)
			(layer "B.Fab")
			(hide yes)
			(effects
				(font
					(size 1 1)
					(thickness 0.15)
				)
				(justify mirror)
			)
		)
		(property "License" "Apache-2.0"
			(at 382.6 -98.5 0)
			(layer "B.Fab")
			(hide yes)
			(effects
				(font
					(size 1 1)
					(thickness 0.15)
				)
				(justify mirror)
			)
		)
		(property "MPN" "BSS138PW"
			(at 382.6 -98.5 0)
			(layer "B.Fab")
			(hide yes)
			(effects
				(font
					(size 1 1)
					(thickness 0.15)
				)
				(justify mirror)
			)
		)
		(property "Manufacturer" "Nexperia"
			(at 382.6 -98.5 0)
			(layer "B.Fab")
			(hide yes)
			(effects
				(font
					(size 1 1)
					(thickness 0.15)
				)
				(justify mirror)
			)
		)
		(sheetname "USB PHY")
		(sheetfile "usb-phy.kicad_sch")
		(attr smd)
		(fp_line
			(start -0.3 -1)
			(end 0.627 -1.001)
			(stroke
				(width 0.15)
				(type solid)
			)
			(layer "B.SilkS")
		)
		(fp_line
			(start 0.627 -0.6)
			(end 0.627 -1.001)
			(stroke
				(width 0.15)
				(type solid)
			)
			(layer "B.SilkS")
		)
		(fp_line
			(start 0.627 0.6)
			(end 0.627 0.999)
			(stroke
				(width 0.15)
				(type solid)
			)
			(layer "B.SilkS")
		)
		(fp_line
			(start -0.3 1)
			(end 0.627 0.999)
			(stroke
				(width 0.15)
				(type solid)
			)
			(layer "B.SilkS")
		)
		(fp_line
			(start 0.9 -1.3)
			(end -0.9 -1.3)
			(stroke
				(width 0.05)
				(type solid)
			)
			(layer "B.CrtYd")
		)
		(fp_line
			(start -0.9 -1.3)
			(end -0.9 -1)
			(stroke
				(width 0.05)
				(type solid)
			)
			(layer "B.CrtYd")
		)
		(fp_line
			(start -0.9 -1)
			(end -1.4 -1)
			(stroke
				(width 0.05)
				(type solid)
			)
			(layer "B.CrtYd")
		)
		(fp_line
			(start -1.4 -1)
			(end -1.4 1)
			(stroke
				(width 0.05)
				(type solid)
			)
			(layer "B.CrtYd")
		)
		(fp_line
			(start 1.4 -0.4)
			(end 0.9 -0.4)
			(stroke
				(width 0.05)
				(type solid)
			)
			(layer "B.CrtYd")
		)
		(fp_line
			(start 0.9 -0.4)
			(end 0.9 -1.3)
			(stroke
				(width 0.05)
				(type solid)
			)
			(layer "B.CrtYd")
		)
		(fp_line
			(start 1.4 0.4)
			(end 1.4 -0.4)
			(stroke
				(width 0.05)
				(type solid)
			)
			(layer "B.CrtYd")
		)
		(fp_line
			(start 0.9 0.4)
			(end 1.4 0.4)
			(stroke
				(width 0.05)
				(type solid)
			)
			(layer "B.CrtYd")
		)
		(fp_line
			(start -0.9 1)
			(end -1.4 1)
			(stroke
				(width 0.05)
				(type solid)
			)
			(layer "B.CrtYd")
		)
		(fp_line
			(start 0.9 1.3)
			(end 0.9 0.4)
			(stroke
				(width 0.05)
				(type solid)
			)
			(layer "B.CrtYd")
		)
		(fp_line
			(start -0.9 1.3)
			(end -0.9 1)
			(stroke
				(width 0.05)
				(type solid)
			)
			(layer "B.CrtYd")
		)
		(fp_line
			(start -0.9 1.3)
			(end 0.9 1.3)
			(stroke
				(width 0.05)
				(type solid)
			)
			(layer "B.CrtYd")
		)
		(fp_rect
			(start -0.623 0.999)
			(end 0.627 -1.001)
			(stroke
				(width 0.15)
				(type solid)
			)
			(fill no)
			(layer "B.Fab")
		)
		(pad "1" smd rect
			(at -1.051 0.65)
			(size 0.6 0.6)
			(layers "B.Cu" "B.Mask" "B.Paste")
			(net 343 "Net-(Q17-G)")
			(pinfunction "G")
			(pintype "passive")
		)
		(pad "2" smd rect
			(at -1.051 -0.65)
			(size 0.6 0.6)
			(layers "B.Cu" "B.Mask" "B.Paste")
			(net 1 "GND")
			(pinfunction "S")
			(pintype "passive")
		)
		(pad "3" smd rect
			(at 1.05 0)
			(size 0.6 0.6)
			(layers "B.Cu" "B.Mask" "B.Paste")
			(net 878 "/USB PHY/~{BDBUS3}")
			(pinfunction "D")
			(pintype "passive")
		)
	)
	(footprint "antmicro-footprints:R_0603_1608Metric"
		(layer "B.Cu")
		(at 250.401 170.3)
		(descr "Resistor SMD 0603")
		(tags "resistor SMD 0603")
		(property "Reference" "R262"
			(at 1.309 1.4 180)
			(layer "B.SilkS")
			(effects
				(font
					(size 0.7 0.7)
					(thickness 0.15)
				)
				(justify left bottom mirror)
			)
		)
		(property "Value" "R_220R_0603"
			(at 0 -1.6 180)
			(layer "B.Fab")
			(effects
				(font
					(size 0.7 0.7)
					(thickness 0.15)
				)
				(justify left bottom mirror)
			)
		)
		(property "Description" "SMD Chip Resistor, 220 ohm, ± 1%, 100 mW, 0603 [1608 Metric], Thick Film, General Purpose"
			(at 0 0 0)
			(layer "F.Fab")
			(hide yes)
			(effects
				(font
					(size 1.27 1.27)
					(thickness 0.15)
				)
			)
		)
		(property "Author" "Antmicro"
			(at 0 0 0)
			(layer "B.Fab")
			(hide yes)
			(effects
				(font
					(size 1 1)
					(thickness 0.15)
				)
				(justify mirror)
			)
		)
		(property "License" "Apache-2.0"
			(at 0 0 0)
			(layer "B.Fab")
			(hide yes)
			(effects
				(font
					(size 1 1)
					(thickness 0.15)
				)
				(justify mirror)
			)
		)
		(property "MPN" "CR0603-FX-2200ELF"
			(at 0 0 0)
			(layer "B.Fab")
			(hide yes)
			(effects
				(font
					(size 1 1)
					(thickness 0.15)
				)
				(justify mirror)
			)
		)
		(property "Manufacturer" "Bourns"
			(at 0 0 0)
			(layer "B.Fab")
			(hide yes)
			(effects
				(font
					(size 1 1)
					(thickness 0.15)
				)
				(justify mirror)
			)
		)
		(property "Tolerance" "1%"
			(at 0 0 0)
			(layer "B.Fab")
			(hide yes)
			(effects
				(font
					(size 1 1)
					(thickness 0.15)
				)
				(justify mirror)
			)
		)
		(property "Val" "220R"
			(at 0 0 0)
			(layer "B.Fab")
			(hide yes)
			(effects
				(font
					(size 1 1)
					(thickness 0.15)
				)
				(justify mirror)
			)
		)
		(sheetname "HDMI + Ethernet")
		(sheetfile "hdmi-ethernet.kicad_sch")
		(attr smd)
		(fp_line
			(start -0.15 -0.4)
			(end 0.15 -0.4)
			(stroke
				(width 0.15)
				(type solid)
			)
			(layer "B.SilkS")
		)
		(fp_line
			(start -0.15 0.4)
			(end 0.15 0.4)
			(stroke
				(width 0.15)
				(type solid)
			)
			(layer "B.SilkS")
		)
		(fp_rect
			(start -1.25 0.65)
			(end 1.25 -0.65)
			(stroke
				(width 0.05)
				(type solid)
			)
			(fill no)
			(layer "B.CrtYd")
		)
		(fp_rect
			(start -0.8 0.4)
			(end 0.8 -0.4)
			(stroke
				(width 0.15)
				(type solid)
			)
			(fill no)
			(layer "B.Fab")
		)
		(pad "1" smd roundrect
			(at -0.7 0)
			(size 0.8 1)
			(layers "B.Cu" "B.Mask" "B.Paste")
			(roundrect_rratio 0.2)
			(net 849 "/HDMI + Ethernet/GBE_LED_LINK+")
			(pintype "passive")
		)
		(pad "2" smd roundrect
			(at 0.7 0)
			(size 0.8 1)
			(layers "B.Cu" "B.Mask" "B.Paste")
			(roundrect_rratio 0.2)
			(net 24 "+3V3")
			(pintype "passive")
		)
	)
	(footprint "antmicro-footprints:R_0402_1005Metric"
		(layer "B.Cu")
		(at 227.1 155.2 180)
		(descr "Resistor SMD 0402")
		(tags "resistor SMD 0402")
		(property "Reference" "R230"
			(at 0.725 -0.375 0)
			(layer "B.SilkS")
			(effects
				(font
					(size 0.7 0.7)
					(thickness 0.15)
				)
				(justify left bottom mirror)
			)
		)
		(property "Value" "R_2k2_0402"
			(at 0 -1.4 0)
			(layer "B.Fab")
			(effects
				(font
					(size 0.7 0.7)
					(thickness 0.15)
				)
				(justify left bottom mirror)
			)
		)
		(property "Description" "SMD Chip Resistor, 2.2 kohm, ± 1%, 62.5 mW, 0402 [1005 Metric], Thick Film, General Purpose"
			(at 0 0 180)
			(layer "F.Fab")
			(hide yes)
			(effects
				(font
					(size 1.27 1.27)
					(thickness 0.15)
				)
			)
		)
		(property "Author" "Antmicro"
			(at 454.2 310.4 0)
			(layer "B.Fab")
			(hide yes)
			(effects
				(font
					(size 1 1)
					(thickness 0.15)
				)
				(justify mirror)
			)
		)
		(property "License" "Apache-2.0"
			(at 454.2 310.4 0)
			(layer "B.Fab")
			(hide yes)
			(effects
				(font
					(size 1 1)
					(thickness 0.15)
				)
				(justify mirror)
			)
		)
		(property "MPN" "CR0402-FX-2201GLF"
			(at 454.2 310.4 0)
			(layer "B.Fab")
			(hide yes)
			(effects
				(font
					(size 1 1)
					(thickness 0.15)
				)
				(justify mirror)
			)
		)
		(property "Manufacturer" "Bourns"
			(at 454.2 310.4 0)
			(layer "B.Fab")
			(hide yes)
			(effects
				(font
					(size 1 1)
					(thickness 0.15)
				)
				(justify mirror)
			)
		)
		(property "Tolerance" "1%"
			(at 454.2 310.4 0)
			(layer "B.Fab")
			(hide yes)
			(effects
				(font
					(size 1 1)
					(thickness 0.15)
				)
				(justify mirror)
			)
		)
		(property "Val" "2k2"
			(at 454.2 310.4 0)
			(layer "B.Fab")
			(hide yes)
			(effects
				(font
					(size 1 1)
					(thickness 0.15)
				)
				(justify mirror)
			)
		)
		(sheetname "HDMI + Ethernet")
		(sheetfile "hdmi-ethernet.kicad_sch")
		(attr smd)
		(fp_rect
			(start -0.925 0.47)
			(end 0.925 -0.47)
			(stroke
				(width 0.05)
				(type default)
			)
			(fill no)
			(layer "B.CrtYd")
		)
		(fp_rect
			(start -0.5 0.25)
			(end 0.5 -0.25)
			(stroke
				(width 0.15)
				(type solid)
			)
			(fill no)
			(layer "B.Fab")
		)
		(pad "1" smd roundrect
			(at -0.48 0 180)
			(size 0.59 0.64)
			(layers "B.Cu" "B.Mask" "B.Paste")
			(roundrect_rratio 0.25)
			(net 846 "/HDMI + Ethernet/ETH_LED_SPD-")
			(pintype "passive")
		)
		(pad "2" smd roundrect
			(at 0.48 0 180)
			(size 0.59 0.64)
			(layers "B.Cu" "B.Mask" "B.Paste")
			(roundrect_rratio 0.25)
			(net 1 "GND")
			(pintype "passive")
		)
	)
	(footprint "antmicro-footprints:R_0402_1005Metric"
		(layer "B.Cu")
		(at 266.001 125.7)
		(descr "Resistor SMD 0402")
		(tags "resistor SMD 0402")
		(property "Reference" "R171"
			(at -0.901 0.675 180)
			(layer "B.SilkS")
			(effects
				(font
					(size 0.7 0.7)
					(thickness 0.15)
				)
				(justify left bottom mirror)
			)
		)
		(property "Value" "R_1k5_0402"
			(at 0 -1.4 180)
			(layer "B.Fab")
			(effects
				(font
					(size 0.7 0.7)
					(thickness 0.15)
				)
				(justify left bottom mirror)
			)
		)
		(property "Description" "SMD Chip Resistor, 1.5 kohm, ± 1%, 62.5 mW, 0402 [1005 Metric], Thick Film, General Purpose"
			(at 0 0 0)
			(layer "F.Fab")
			(hide yes)
			(effects
				(font
					(size 1.27 1.27)
					(thickness 0.15)
				)
			)
		)
		(property "Author" "Antmicro"
			(at 0 0 0)
			(layer "B.Fab")
			(hide yes)
			(effects
				(font
					(size 1 1)
					(thickness 0.15)
				)
				(justify mirror)
			)
		)
		(property "License" "Apache-2.0"
			(at 0 0 0)
			(layer "B.Fab")
			(hide yes)
			(effects
				(font
					(size 1 1)
					(thickness 0.15)
				)
				(justify mirror)
			)
		)
		(property "MPN" "CR0402-FX-1501GLF"
			(at 0 0 0)
			(layer "B.Fab")
			(hide yes)
			(effects
				(font
					(size 1 1)
					(thickness 0.15)
				)
				(justify mirror)
			)
		)
		(property "Manufacturer" "Bourns"
			(at 0 0 0)
			(layer "B.Fab")
			(hide yes)
			(effects
				(font
					(size 1 1)
					(thickness 0.15)
				)
				(justify mirror)
			)
		)
		(property "Tolerance" "1%"
			(at 0 0 0)
			(layer "B.Fab")
			(hide yes)
			(effects
				(font
					(size 1 1)
					(thickness 0.15)
				)
				(justify mirror)
			)
		)
		(property "Val" "1k5"
			(at 0 0 0)
			(layer "B.Fab")
			(hide yes)
			(effects
				(font
					(size 1 1)
					(thickness 0.15)
				)
				(justify mirror)
			)
		)
		(sheetname "USB PHY")
		(sheetfile "usb-phy.kicad_sch")
		(attr smd)
		(fp_rect
			(start -0.925 0.47)
			(end 0.925 -0.47)
			(stroke
				(width 0.05)
				(type default)
			)
			(fill no)
			(layer "B.CrtYd")
		)
		(fp_rect
			(start -0.5 0.25)
			(end 0.5 -0.25)
			(stroke
				(width 0.15)
				(type solid)
			)
			(fill no)
			(layer "B.Fab")
		)
		(pad "1" smd roundrect
			(at -0.48 0)
			(size 0.59 0.64)
			(layers "B.Cu" "B.Mask" "B.Paste")
			(roundrect_rratio 0.25)
			(net 842 "/USB PHY/USB_USR_CONN_D+")
			(pintype "passive")
		)
		(pad "2" smd roundrect
			(at 0.48 0)
			(size 0.59 0.64)
			(layers "B.Cu" "B.Mask" "B.Paste")
			(roundrect_rratio 0.25)
			(net 926 "/USB PHY/USB_USR_VPU")
			(pintype "passive")
		)
	)
)
